(kicad_pcb
	(version 20260206)
	(generator "pcbnew")
	(generator_version "10.0")
	(general
		(thickness 1.6)
		(legacy_teardrops no)
	)
	(paper "A4")
	(title_block
		(title "03242023_DA0F0TMBIJ0_F0T_Motherboard_J_brd_V01_OCP.brd")
		(comment 1 "Grand Teton / footprint 3039 of 6105 (U2), pads 1708-1819 of 4677")
	)
	(layers
		(0 "F.Cu" signal "TOP")
		(4 "In1.Cu" signal "GND")
		(6 "In2.Cu" signal "IN1")
		(8 "In3.Cu" signal "GND1")
		(10 "In4.Cu" signal "IN2")
		(12 "In5.Cu" signal "GND2")
		(14 "In6.Cu" signal "IN3")
		(16 "In7.Cu" signal "GND3")
		(18 "In8.Cu" signal "VCC")
		(20 "In9.Cu" signal "VCC1")
		(22 "In10.Cu" signal "GND4")
		(24 "In11.Cu" signal "IN4")
		(26 "In12.Cu" signal "GND5")
		(28 "In13.Cu" signal "IN5")
		(30 "In14.Cu" signal "GND6")
		(32 "In15.Cu" signal "IN6")
		(34 "In16.Cu" signal "GND7")
		(2 "B.Cu" signal "BOTTOM")
		(9 "F.Adhes" user "F.Adhesive")
		(11 "B.Adhes" user "B.Adhesive")
		(13 "F.Paste" user "Package Geometry/Pastemask Top")
		(15 "B.Paste" user "Package Geometry/Pastemask Bottom")
		(5 "F.SilkS" user "Ref Des/Silkscreen Top")
		(7 "B.SilkS" user "Ref Des/Silkscreen Bottom")
		(1 "F.Mask" user "Board Geometry/Soldermask Top")
		(3 "B.Mask" user "Board Geometry/Soldermask Bottom")
		(17 "Dwgs.User" user "User.Drawings")
		(19 "Cmts.User" user "User.Comments")
		(21 "Eco1.User" user "User.Eco1")
		(23 "Eco2.User" user "User.Eco2")
		(25 "Edge.Cuts" user "Board Geometry/Outline")
		(27 "Margin" user)
		(31 "F.CrtYd" user "Package Geometry/Place Bound Top")
		(29 "B.CrtYd" user "Package Geometry/Place Bound Bottom")
		(35 "F.Fab" user "Ref Des/Assembly Top")
		(33 "B.Fab" user "Ref Des/Assembly Bottom")
	)
	(footprint ""
		(layer "F.Cu")
		(at 359.870248 -251.76988 90)
		(property "Reference" "U2"
			(at -74.416158 -44.488608 0)
			(unlocked yes)
			(layer "F.SilkS")
			(effects
				(font
					(size 1.6002 1.1938)
					(thickness 0.1524)
				)
				(justify left)
			)
		)
		(property "Value" ""
			(at 0 0 90)
			(layer "F.Fab")
			(effects
				(font
					(size 1.27 1.27)
				)
			)
		)
		(duplicate_pad_numbers_are_jumpers no)
		(pad "CA66" smd circle
			(at 17.07769 1.229614 270)
			(size 0.4318 0.4318)
			(layers "F.Cu" "F.Mask" "F.Paste")
			(net "PVCCIN_CPU0")
		)
		(pad "CA68" smd circle
			(at 18.705576 1.229614 270)
			(size 0.4318 0.4318)
			(layers "F.Cu" "F.Mask" "F.Paste")
			(net "PVCCIN_CPU0")
		)
		(pad "CA70" smd circle
			(at 20.333462 1.229614 270)
			(size 0.4318 0.4318)
			(layers "F.Cu" "F.Mask" "F.Paste")
			(net "PVCCIN_CPU0")
		)
		(pad "CA72" smd circle
			(at 21.961094 1.229614 270)
			(size 0.4318 0.4318)
			(layers "F.Cu" "F.Mask" "F.Paste")
			(net "PVCCIN_CPU0")
		)
		(pad "CA74" smd circle
			(at 23.58898 1.229614 270)
			(size 0.4318 0.4318)
			(layers "F.Cu" "F.Mask" "F.Paste")
			(net "PVCCIN_CPU0")
		)
		(pad "CA76" smd circle
			(at 25.216612 1.229614 270)
			(size 0.4318 0.4318)
			(layers "F.Cu" "F.Mask" "F.Paste")
			(net "PVCCIN_CPU0")
		)
		(pad "CA78" smd circle
			(at 26.844498 1.229614 270)
			(size 0.4318 0.4318)
			(layers "F.Cu" "F.Mask" "F.Paste")
			(net "PVCCIN_CPU0")
		)
		(pad "CA80" smd circle
			(at 28.472384 1.229614 270)
			(size 0.4318 0.4318)
			(layers "F.Cu" "F.Mask" "F.Paste")
			(net "PVCCIN_CPU0")
		)
		(pad "CA82" smd circle
			(at 30.100016 1.229614 270)
			(size 0.4318 0.4318)
			(layers "F.Cu" "F.Mask" "F.Paste")
			(net "PVCCIN_CPU0")
		)
		(pad "CA84" smd circle
			(at 31.727902 1.229614 270)
			(size 0.4318 0.4318)
			(layers "F.Cu" "F.Mask" "F.Paste")
			(net "PVCCIN_CPU0")
		)
		(pad "CA86" smd circle
			(at 33.355534 1.229614 270)
			(size 0.4318 0.4318)
			(layers "F.Cu" "F.Mask" "F.Paste")
			(net "PVCCIN_CPU0")
		)
		(pad "CA88" smd circle
			(at 34.98342 1.229614 270)
			(size 0.4318 0.4318)
			(layers "F.Cu" "F.Mask" "F.Paste")
			(net "PVCCIN_CPU0")
		)
		(pad "CA90" smd oval
			(at 36.611306 1.229614)
			(size 0.381 0.4826)
			(drill
				(offset 0 -0.0508)
			)
			(layers "F.Cu" "F.Mask" "F.Paste")
			(net "PVCCIN_CPU0")
		)
		(pad "CB2" smd oval
			(at -36.611306 1.589532 180)
			(size 0.381 0.4826)
			(drill
				(offset 0 -0.0508)
			)
			(layers "F.Cu" "F.Mask" "F.Paste")
			(net "UPI_CPU1_CPU0_P0P1_DP<23>")
		)
		(pad "CB4" smd circle
			(at -34.98342 1.589532 270)
			(size 0.4318 0.4318)
			(layers "F.Cu" "F.Mask" "F.Paste")
			(net "GND")
		)
		(pad "CB6" smd circle
			(at -33.355534 1.589532 270)
			(size 0.4318 0.4318)
			(layers "F.Cu" "F.Mask" "F.Paste")
			(net "UPI_CPU0_CPU1_P1P0_DP<22>")
		)
		(pad "CB8" smd circle
			(at -31.727902 1.589532 270)
			(size 0.4318 0.4318)
			(layers "F.Cu" "F.Mask" "F.Paste")
			(net "GND")
		)
		(pad "CB10" smd circle
			(at -30.100016 1.589532 270)
			(size 0.4318 0.4318)
			(layers "F.Cu" "F.Mask" "F.Paste")
			(net "P5E_CPU0_PE1_RX_DN<6>")
		)
		(pad "CB12" smd circle
			(at -28.472384 1.589532 270)
			(size 0.4318 0.4318)
			(layers "F.Cu" "F.Mask" "F.Paste")
			(net "GND")
		)
		(pad "CB14" smd circle
			(at -26.844498 1.589532 270)
			(size 0.4318 0.4318)
			(layers "F.Cu" "F.Mask" "F.Paste")
			(net "P5E_CPU0_PE1_TX_DN<6>")
		)
		(pad "CB16" smd circle
			(at -25.216612 1.589532 270)
			(size 0.4318 0.4318)
			(layers "F.Cu" "F.Mask" "F.Paste")
			(net "GND")
		)
		(pad "CB18" smd circle
			(at -23.58898 1.589532 270)
			(size 0.4318 0.4318)
			(layers "F.Cu" "F.Mask" "F.Paste")
			(net "DMI_CPU0_PCH_TX_DP<2>")
		)
		(pad "CB20" smd circle
			(at -21.961094 1.589532 270)
			(size 0.4318 0.4318)
			(layers "F.Cu" "F.Mask" "F.Paste")
			(net "GND")
		)
		(pad "CB22" smd circle
			(at -20.333462 1.589532 270)
			(size 0.4318 0.4318)
			(layers "F.Cu" "F.Mask" "F.Paste")
			(net "GND")
		)
		(pad "CB24" smd circle
			(at -18.705576 1.589532 270)
			(size 0.4318 0.4318)
			(layers "F.Cu" "F.Mask" "F.Paste")
			(net "GND")
		)
		(pad "CB26" smd circle
			(at -17.07769 1.589532 270)
			(size 0.4318 0.4318)
			(layers "F.Cu" "F.Mask" "F.Paste")
			(net "GND")
		)
		(pad "CB28" smd circle
			(at -15.450058 1.589532 270)
			(size 0.4318 0.4318)
			(layers "F.Cu" "F.Mask" "F.Paste")
			(net "GND")
		)
		(pad "CB30" smd circle
			(at -13.822426 1.589532 270)
			(size 0.4318 0.4318)
			(layers "F.Cu" "F.Mask" "F.Paste")
			(net "TP_TRC_CPU0_PTI0_CLK")
		)
		(pad "CB32" smd circle
			(at -12.19454 1.589532 270)
			(size 0.4318 0.4318)
			(layers "F.Cu" "F.Mask" "F.Paste")
			(net "GND")
		)
		(pad "CB34" smd circle
			(at -10.566654 1.589532 270)
			(size 0.4318 0.4318)
			(layers "F.Cu" "F.Mask" "F.Paste")
			(net "GND")
		)
		(pad "CB36" smd circle
			(at -8.939022 1.589532 270)
			(size 0.4318 0.4318)
			(layers "F.Cu" "F.Mask" "F.Paste")
			(net "GND")
		)
		(pad "CB38" smd circle
			(at -7.311136 1.589532 270)
			(size 0.4318 0.4318)
			(layers "F.Cu" "F.Mask" "F.Paste")
			(net "GND")
		)
		(pad "CB40" smd circle
			(at -5.68325 1.589532 270)
			(size 0.4318 0.4318)
			(layers "F.Cu" "F.Mask" "F.Paste")
			(net "GND")
		)
		(pad "CB42" smd circle
			(at -4.055618 1.589532 270)
			(size 0.4318 0.4318)
			(layers "F.Cu" "F.Mask" "F.Paste")
			(net "GND")
		)
		(pad "CB44" smd circle
			(at -2.427732 1.589532 270)
			(size 0.4318 0.4318)
			(layers "F.Cu" "F.Mask" "F.Paste")
			(net "GND")
		)
		(pad "CB47" smd circle
			(at 1.613916 1.699514 270)
			(size 0.4318 0.4318)
			(layers "F.Cu" "F.Mask" "F.Paste")
			(net "GND")
		)
		(pad "CB49" smd circle
			(at 3.241802 1.699514 270)
			(size 0.4318 0.4318)
			(layers "F.Cu" "F.Mask" "F.Paste")
			(net "GND")
		)
		(pad "CB51" smd circle
			(at 4.869434 1.699514 270)
			(size 0.4318 0.4318)
			(layers "F.Cu" "F.Mask" "F.Paste")
			(net "GND")
		)
		(pad "CB53" smd circle
			(at 6.49732 1.699514 270)
			(size 0.4318 0.4318)
			(layers "F.Cu" "F.Mask" "F.Paste")
			(net "GND")
		)
		(pad "CB55" smd circle
			(at 8.124952 1.699514 270)
			(size 0.4318 0.4318)
			(layers "F.Cu" "F.Mask" "F.Paste")
			(net "GND")
		)
		(pad "CB57" smd circle
			(at 9.752838 1.699514 270)
			(size 0.4318 0.4318)
			(layers "F.Cu" "F.Mask" "F.Paste")
			(net "GND")
		)
		(pad "CB59" smd circle
			(at 11.380724 1.699514 270)
			(size 0.4318 0.4318)
			(layers "F.Cu" "F.Mask" "F.Paste")
			(net "GND")
		)
		(pad "CB61" smd circle
			(at 13.008356 1.699514 270)
			(size 0.4318 0.4318)
			(layers "F.Cu" "F.Mask" "F.Paste")
			(net "PVCCIN_CPU0")
		)
		(pad "CB63" smd circle
			(at 14.635988 1.699514 270)
			(size 0.4318 0.4318)
			(layers "F.Cu" "F.Mask" "F.Paste")
			(net "GND")
		)
		(pad "CB65" smd circle
			(at 16.263874 1.699514 270)
			(size 0.4318 0.4318)
			(layers "F.Cu" "F.Mask" "F.Paste")
			(net "GND")
		)
		(pad "CB67" smd circle
			(at 17.89176 1.699514 270)
			(size 0.4318 0.4318)
			(layers "F.Cu" "F.Mask" "F.Paste")
			(net "GND")
		)
		(pad "CB69" smd circle
			(at 19.519392 1.699514 270)
			(size 0.4318 0.4318)
			(layers "F.Cu" "F.Mask" "F.Paste")
			(net "GND")
		)
		(pad "CB71" smd circle
			(at 21.147278 1.699514 270)
			(size 0.4318 0.4318)
			(layers "F.Cu" "F.Mask" "F.Paste")
			(net "GND")
		)
		(pad "CB73" smd circle
			(at 22.77491 1.699514 270)
			(size 0.4318 0.4318)
			(layers "F.Cu" "F.Mask" "F.Paste")
			(net "GND")
		)
		(pad "CB75" smd circle
			(at 24.402796 1.699514 270)
			(size 0.4318 0.4318)
			(layers "F.Cu" "F.Mask" "F.Paste")
			(net "PVCCIN_CPU0")
		)
		(pad "CB77" smd circle
			(at 26.030682 1.699514 270)
			(size 0.4318 0.4318)
			(layers "F.Cu" "F.Mask" "F.Paste")
			(net "PVCCIN_CPU0")
		)
		(pad "CB79" smd circle
			(at 27.658314 1.699514 270)
			(size 0.4318 0.4318)
			(layers "F.Cu" "F.Mask" "F.Paste")
			(net "GND")
		)
		(pad "CB81" smd circle
			(at 29.2862 1.699514 270)
			(size 0.4318 0.4318)
			(layers "F.Cu" "F.Mask" "F.Paste")
			(net "GND")
		)
		(pad "CB83" smd circle
			(at 30.914086 1.699514 270)
			(size 0.4318 0.4318)
			(layers "F.Cu" "F.Mask" "F.Paste")
			(net "GND")
		)
		(pad "CB85" smd circle
			(at 32.541718 1.699514 270)
			(size 0.4318 0.4318)
			(layers "F.Cu" "F.Mask" "F.Paste")
			(net "GND")
		)
		(pad "CB87" smd circle
			(at 34.169604 1.699514 270)
			(size 0.4318 0.4318)
			(layers "F.Cu" "F.Mask" "F.Paste")
			(net "GND")
		)
		(pad "CB89" smd circle
			(at 35.797236 1.699514 270)
			(size 0.4318 0.4318)
			(layers "F.Cu" "F.Mask" "F.Paste")
			(net "GND")
		)
		(pad "CC3" smd circle
			(at -35.797236 2.059686 270)
			(size 0.4318 0.4318)
			(layers "F.Cu" "F.Mask" "F.Paste")
			(net "UPI_CPU1_CPU0_P0P1_DN<22>")
		)
		(pad "CC5" smd circle
			(at -34.169604 2.059686 270)
			(size 0.4318 0.4318)
			(layers "F.Cu" "F.Mask" "F.Paste")
			(net "GND")
		)
		(pad "CC7" smd circle
			(at -32.541718 2.059686 270)
			(size 0.4318 0.4318)
			(layers "F.Cu" "F.Mask" "F.Paste")
			(net "UPI_CPU0_CPU1_P1P0_DN<21>")
		)
		(pad "CC9" smd circle
			(at -30.914086 2.059686 270)
			(size 0.4318 0.4318)
			(layers "F.Cu" "F.Mask" "F.Paste")
			(net "GND")
		)
		(pad "CC11" smd circle
			(at -29.2862 2.059686 270)
			(size 0.4318 0.4318)
			(layers "F.Cu" "F.Mask" "F.Paste")
			(net "P5E_CPU0_PE1_RX_DN<5>")
		)
		(pad "CC13" smd circle
			(at -27.658314 2.059686 270)
			(size 0.4318 0.4318)
			(layers "F.Cu" "F.Mask" "F.Paste")
			(net "GND")
		)
		(pad "CC15" smd circle
			(at -26.030682 2.059686 270)
			(size 0.4318 0.4318)
			(layers "F.Cu" "F.Mask" "F.Paste")
			(net "P5E_CPU0_PE1_TX_DP<6>")
		)
		(pad "CC17" smd circle
			(at -24.402796 2.059686 270)
			(size 0.4318 0.4318)
			(layers "F.Cu" "F.Mask" "F.Paste")
			(net "GND")
		)
		(pad "CC19" smd circle
			(at -22.77491 2.059686 270)
			(size 0.4318 0.4318)
			(layers "F.Cu" "F.Mask" "F.Paste")
			(net "DMI_CPU0_PCH_TX_DN<2>")
		)
		(pad "CC21" smd circle
			(at -21.147278 2.059686 270)
			(size 0.4318 0.4318)
			(layers "F.Cu" "F.Mask" "F.Paste")
			(net "NC_CPU0_PE1_APROBE<1>")
		)
		(pad "CC23" smd circle
			(at -19.519392 2.059686 270)
			(size 0.4318 0.4318)
			(layers "F.Cu" "F.Mask" "F.Paste")
			(net "NC_CPU0_PE2_APROBE<0>")
		)
		(pad "CC25" smd circle
			(at -17.89176 2.059686 270)
			(size 0.4318 0.4318)
			(layers "F.Cu" "F.Mask" "F.Paste")
			(net "TP_H_SBLINK7_CPU0_PMDOWN")
		)
		(pad "CC27" smd circle
			(at -16.263874 2.059686 270)
			(size 0.4318 0.4318)
			(layers "F.Cu" "F.Mask" "F.Paste")
			(net "TP_TRC_CPU0_PTI<2>")
		)
		(pad "CC29" smd circle
			(at -14.635988 2.059686 270)
			(size 0.4318 0.4318)
			(layers "F.Cu" "F.Mask" "F.Paste")
			(net "TP_TP_TRC_CPU0_PTI_MON<0>")
		)
		(pad "CC31" smd circle
			(at -13.008356 2.059686 270)
			(size 0.4318 0.4318)
			(layers "F.Cu" "F.Mask" "F.Paste")
			(net "GND")
		)
		(pad "CC33" smd circle
			(at -11.380724 2.059686 270)
			(size 0.4318 0.4318)
			(layers "F.Cu" "F.Mask" "F.Paste")
			(net "PVCCIN_CPU0")
		)
		(pad "CC35" smd circle
			(at -9.752838 2.059686 270)
			(size 0.4318 0.4318)
			(layers "F.Cu" "F.Mask" "F.Paste")
			(net "PVCCIN_CPU0")
		)
		(pad "CC37" smd circle
			(at -8.124952 2.059686 270)
			(size 0.4318 0.4318)
			(layers "F.Cu" "F.Mask" "F.Paste")
			(net "PVCCIN_CPU0")
		)
		(pad "CC39" smd circle
			(at -6.49732 2.059686 270)
			(size 0.4318 0.4318)
			(layers "F.Cu" "F.Mask" "F.Paste")
			(net "PVCCIN_CPU0")
		)
		(pad "CC41" smd circle
			(at -4.869434 2.059686 270)
			(size 0.4318 0.4318)
			(layers "F.Cu" "F.Mask" "F.Paste")
			(net "PVCCIN_CPU0")
		)
		(pad "CC43" smd circle
			(at -3.241802 2.059686 270)
			(size 0.4318 0.4318)
			(layers "F.Cu" "F.Mask" "F.Paste")
			(net "PVCCIN_CPU0")
		)
		(pad "CC45" smd circle
			(at -1.613916 2.059686 270)
			(size 0.4318 0.4318)
			(layers "F.Cu" "F.Mask" "F.Paste")
			(net "PVCCIN_CPU0")
		)
		(pad "CC48" smd circle
			(at 2.427732 2.169668 270)
			(size 0.4318 0.4318)
			(layers "F.Cu" "F.Mask" "F.Paste")
			(net "PVCCIN_CPU0")
		)
		(pad "CC50" smd circle
			(at 4.055618 2.169668 270)
			(size 0.4318 0.4318)
			(layers "F.Cu" "F.Mask" "F.Paste")
			(net "PVCCIN_CPU0")
		)
		(pad "CC52" smd circle
			(at 5.68325 2.169668 270)
			(size 0.4318 0.4318)
			(layers "F.Cu" "F.Mask" "F.Paste")
			(net "PVCCIN_CPU0")
		)
		(pad "CC54" smd circle
			(at 7.311136 2.169668 270)
			(size 0.4318 0.4318)
			(layers "F.Cu" "F.Mask" "F.Paste")
			(net "PVCCIN_CPU0")
		)
		(pad "CC56" smd circle
			(at 8.939022 2.169668 270)
			(size 0.4318 0.4318)
			(layers "F.Cu" "F.Mask" "F.Paste")
			(net "PVCCIN_CPU0")
		)
		(pad "CC58" smd circle
			(at 10.566654 2.169668 270)
			(size 0.4318 0.4318)
			(layers "F.Cu" "F.Mask" "F.Paste")
			(net "PVCCIN_CPU0")
		)
		(pad "CC60" smd circle
			(at 12.19454 2.169668 270)
			(size 0.4318 0.4318)
			(layers "F.Cu" "F.Mask" "F.Paste")
			(net "PVCCIN_CPU0")
		)
		(pad "CC62" smd circle
			(at 13.822426 2.169668 270)
			(size 0.4318 0.4318)
			(layers "F.Cu" "F.Mask" "F.Paste")
			(net "GND")
		)
		(pad "CC64" smd circle
			(at 15.450058 2.169668 270)
			(size 0.4318 0.4318)
			(layers "F.Cu" "F.Mask" "F.Paste")
			(net "NC_CPU0_LGSSPARE4")
		)
		(pad "CC66" smd circle
			(at 17.07769 2.169668 270)
			(size 0.4318 0.4318)
			(layers "F.Cu" "F.Mask" "F.Paste")
			(net "NC_CPU0_MDFI_DIE01_EW1")
		)
		(pad "CC68" smd circle
			(at 18.705576 2.169668 270)
			(size 0.4318 0.4318)
			(layers "F.Cu" "F.Mask" "F.Paste")
			(net "PVPP_HBM_CPU0")
		)
		(pad "CC70" smd circle
			(at 20.333462 2.169668 270)
			(size 0.4318 0.4318)
			(layers "F.Cu" "F.Mask" "F.Paste")
			(net "GND")
		)
		(pad "CC72" smd circle
			(at 21.961094 2.169668 270)
			(size 0.4318 0.4318)
			(layers "F.Cu" "F.Mask" "F.Paste")
			(net "GND")
		)
		(pad "CC74" smd circle
			(at 23.58898 2.169668 270)
			(size 0.4318 0.4318)
			(layers "F.Cu" "F.Mask" "F.Paste")
			(net "GND")
		)
		(pad "CC76" smd circle
			(at 25.216612 2.169668 270)
			(size 0.4318 0.4318)
			(layers "F.Cu" "F.Mask" "F.Paste")
			(net "PVCCIN_CPU0")
		)
		(pad "CC78" smd circle
			(at 26.844498 2.169668 270)
			(size 0.4318 0.4318)
			(layers "F.Cu" "F.Mask" "F.Paste")
			(net "PVCCIN_CPU0")
		)
		(pad "CC80" smd circle
			(at 28.472384 2.169668 270)
			(size 0.4318 0.4318)
			(layers "F.Cu" "F.Mask" "F.Paste")
			(net "PVCCIN_CPU0")
		)
		(pad "CC82" smd circle
			(at 30.100016 2.169668 270)
			(size 0.4318 0.4318)
			(layers "F.Cu" "F.Mask" "F.Paste")
			(net "PVCCIN_CPU0")
		)
		(pad "CC84" smd circle
			(at 31.727902 2.169668 270)
			(size 0.4318 0.4318)
			(layers "F.Cu" "F.Mask" "F.Paste")
			(net "PVCCIN_CPU0")
		)
		(pad "CC86" smd circle
			(at 33.355534 2.169668 270)
			(size 0.4318 0.4318)
			(layers "F.Cu" "F.Mask" "F.Paste")
			(net "PVCCIN_CPU0")
		)
		(pad "CC88" smd circle
			(at 34.98342 2.169668 270)
			(size 0.4318 0.4318)
			(layers "F.Cu" "F.Mask" "F.Paste")
			(net "PVCCIN_CPU0")
		)
		(pad "CC90" smd oval
			(at 36.611306 2.169668)
			(size 0.381 0.4826)
			(drill
				(offset 0 -0.0508)
			)
			(layers "F.Cu" "F.Mask" "F.Paste")
			(net "PVCCIN_CPU0")
		)
		(pad "CD2" smd oval
			(at -36.611306 2.529586 180)
			(size 0.381 0.4826)
			(drill
				(offset 0 -0.0508)
			)
			(layers "F.Cu" "F.Mask" "F.Paste")
			(net "UPI_CPU1_CPU0_P0P1_DP<22>")
		)
		(pad "CD4" smd circle
			(at -34.98342 2.529586 270)
			(size 0.4318 0.4318)
			(layers "F.Cu" "F.Mask" "F.Paste")
			(net "GND")
		)
		(pad "CD6" smd circle
			(at -33.355534 2.529586 270)
			(size 0.4318 0.4318)
			(layers "F.Cu" "F.Mask" "F.Paste")
			(net "UPI_CPU0_CPU1_P1P0_DP<21>")
		)
		(pad "CD8" smd circle
			(at -31.727902 2.529586 270)
			(size 0.4318 0.4318)
			(layers "F.Cu" "F.Mask" "F.Paste")
			(net "GND")
		)
		(pad "CD10" smd circle
			(at -30.100016 2.529586 270)
			(size 0.4318 0.4318)
			(layers "F.Cu" "F.Mask" "F.Paste")
			(net "P5E_CPU0_PE1_RX_DP<5>")
		)
		(pad "CD12" smd circle
			(at -28.472384 2.529586 270)
			(size 0.4318 0.4318)
			(layers "F.Cu" "F.Mask" "F.Paste")
			(net "GND")
		)
		(pad "CD14" smd circle
			(at -26.844498 2.529586 270)
			(size 0.4318 0.4318)
			(layers "F.Cu" "F.Mask" "F.Paste")
			(net "P5E_CPU0_PE1_TX_DP<5>")
		)
		(pad "CD16" smd circle
			(at -25.216612 2.529586 270)
			(size 0.4318 0.4318)
			(layers "F.Cu" "F.Mask" "F.Paste")
			(net "GND")
		)
		(pad "CD18" smd circle
			(at -23.58898 2.529586 270)
			(size 0.4318 0.4318)
			(layers "F.Cu" "F.Mask" "F.Paste")
			(net "DMI_CPU0_PCH_TX_DN<3>")
		)
		(pad "CD20" smd circle
			(at -21.961094 2.529586 270)
			(size 0.4318 0.4318)
			(layers "F.Cu" "F.Mask" "F.Paste")
			(net "GND")
		)
		(pad "CD22" smd circle
			(at -20.333462 2.529586 270)
			(size 0.4318 0.4318)
			(layers "F.Cu" "F.Mask" "F.Paste")
			(net "NC_CPU0_MDFI_DIE10_NS1")
		)
	)
)
